(kicad_pcb
	(version 20260206)
	(generator "pcbnew")
	(generator_version "10.0")
	(general
		(thickness 1.6)
		(legacy_teardrops no)
	)
	(paper "A4")
	(title_block
		(title "panther-plus-userver — 13130-1b_20150205.brd")
		(comment 1 "Honey Badger (Wiwynn) / footprint 406 of 1509 (DIMM2), pads 128-134 of 210")
	)
	(layers
		(0 "F.Cu" signal "TOP")
		(4 "In1.Cu" signal "L2")
		(6 "In2.Cu" signal "L3")
		(8 "In3.Cu" signal "L4")
		(10 "In4.Cu" signal "L5")
		(12 "In5.Cu" signal "L6")
		(14 "In6.Cu" signal "L7")
		(16 "In7.Cu" signal "L8")
		(18 "In8.Cu" signal "L9")
		(20 "In9.Cu" signal "L10")
		(22 "In10.Cu" signal "L11")
		(2 "B.Cu" signal "BOTTOM")
		(9 "F.Adhes" user "F.Adhesive")
		(11 "B.Adhes" user "B.Adhesive")
		(13 "F.Paste" user "Package Geometry/Pastemask Top")
		(15 "B.Paste" user "Package Geometry/Pastemask Bottom")
		(5 "F.SilkS" user "Ref Des/Silkscreen Top")
		(7 "B.SilkS" user "Ref Des/Silkscreen Bottom")
		(1 "F.Mask" user "Board Geometry/Soldermask Top")
		(3 "B.Mask" user "Board Geometry/Soldermask Bottom")
		(17 "Dwgs.User" user "User.Drawings")
		(19 "Cmts.User" user "User.Comments")
		(21 "Eco1.User" user "User.Eco1")
		(23 "Eco2.User" user "User.Eco2")
		(25 "Edge.Cuts" user "Board Geometry/Outline")
		(27 "Margin" user)
		(31 "F.CrtYd" user "Package Geometry/Place Bound Top")
		(29 "B.CrtYd" user "Package Geometry/Place Bound Bottom")
		(35 "F.Fab" user "Ref Des/Assembly Top")
		(33 "B.Fab" user "Ref Des/Assembly Bottom")
	)
	(footprint ""
		(layer "F.Cu")
		(at 158.500064 -66.699892 180)
		(property "Reference" "DIMM2"
			(at 0 0 180)
			(layer "F.SilkS")
			(hide yes)
			(effects
				(font
					(size 1.27 1.27)
				)
			)
		)
		(property "Value" "DDR3-204P-174-COLAY-1-GP"
			(at -40.682164 -17.468088 180)
			(unlocked yes)
			(layer "F.Fab")
			(hide yes)
			(effects
				(font
					(size 1.016 1.016)
					(thickness 0.1524)
				)
			)
		)
		(property "Device Type" "AS0A626-H8SN-7H-COLAY-1"
			(at -40.682164 -18.992088 180)
			(unlocked yes)
			(layer "F.Fab")
			(hide yes)
			(effects
				(font
					(size 1.016 1.016)
					(thickness 0.1524)
				)
			)
		)
		(duplicate_pad_numbers_are_jumpers no)
		(pad "126" smd custom
			(at 8.24992 -4.106672 180)
			(size 0.1143 0.1143)
			(layers "F.Cu" "F.Mask" "F.Paste")
			(net "M_A_ODT2")
			(options
				(clearance outline)
				(anchor circle)
			)
			(primitives
				(gr_poly
					(pts
						(xy 0 0.9017) (xy -0.03175 0.89916) (xy -0.0635 0.889) (xy -0.09144 0.87376) (xy -0.11684 0.85344)
						(xy -0.13716 0.82804) (xy -0.1524 0.8001) (xy -0.16256 0.76835) (xy -0.1651 0.7366) (xy -0.1651 0.44958)
						(xy -0.17272 0.44196) (xy -0.19812 0.4064) (xy -0.2032 0.39624) (xy -0.20701 0.38735) (xy -0.21209 0.37719)
						(xy -0.2159 0.36703) (xy -0.21844 0.35687) (xy -0.22225 0.34544) (xy -0.22352 0.33528) (xy -0.22606 0.32512)
						(xy -0.22733 0.31369) (xy -0.22733 0.30353) (xy -0.2286 0.2921) (xy -0.22733 0.28067) (xy -0.22733 0.27051)
						(xy -0.22606 0.25908) (xy -0.22352 0.24892) (xy -0.22225 0.23876) (xy -0.21844 0.22733) (xy -0.2159 0.21717)
						(xy -0.21209 0.20701) (xy -0.20701 0.19685) (xy -0.2032 0.18796) (xy -0.19812 0.1778) (xy -0.17272 0.14224)
						(xy -0.1651 0.13462) (xy -0.1651 -0.7366) (xy -0.16256 -0.76835) (xy -0.1524 -0.8001) (xy -0.13716 -0.82804)
						(xy -0.11684 -0.85344) (xy -0.09144 -0.87376) (xy -0.0635 -0.889) (xy -0.03175 -0.89916) (xy 0 -0.9017)
						(xy 0.03175 -0.89916) (xy 0.0635 -0.889) (xy 0.09144 -0.87376) (xy 0.11684 -0.85344) (xy 0.13716 -0.82804)
						(xy 0.1524 -0.8001) (xy 0.16256 -0.76835) (xy 0.1651 -0.7366) (xy 0.1651 0.13462) (xy 0.17272 0.14224)
						(xy 0.19812 0.1778) (xy 0.2032 0.18796) (xy 0.20701 0.19685) (xy 0.21209 0.20701) (xy 0.2159 0.21717)
						(xy 0.21844 0.22733) (xy 0.22225 0.23876) (xy 0.22352 0.24892) (xy 0.22606 0.25908) (xy 0.22733 0.27051)
						(xy 0.22733 0.28067) (xy 0.2286 0.2921) (xy 0.22733 0.30353) (xy 0.22733 0.31369) (xy 0.22606 0.32512)
						(xy 0.22352 0.33528) (xy 0.22225 0.34544) (xy 0.21844 0.35687) (xy 0.2159 0.36703) (xy 0.21209 0.37719)
						(xy 0.20701 0.38735) (xy 0.2032 0.39624) (xy 0.19812 0.4064) (xy 0.17272 0.44196) (xy 0.1651 0.44958)
						(xy 0.1651 0.7366) (xy 0.16256 0.76835) (xy 0.1524 0.8001) (xy 0.13716 0.82804) (xy 0.11684 0.85344)
						(xy 0.09144 0.87376) (xy 0.0635 0.889) (xy 0.03175 0.89916)
					)
					(width 0)
					(fill yes)
				)
			)
		)
		(pad "127" smd custom
			(at 8.549894 4.106672 180)
			(size 0.1143 0.1143)
			(layers "F.Cu" "F.Mask" "F.Paste")
			(net "M_A_CS_N2")
			(options
				(clearance outline)
				(anchor circle)
			)
			(primitives
				(gr_poly
					(pts
						(xy 0 0.9017) (xy -0.03175 0.89916) (xy -0.0635 0.889) (xy -0.09144 0.87376) (xy -0.11684 0.85344)
						(xy -0.13716 0.82804) (xy -0.1524 0.8001) (xy -0.16256 0.76835) (xy -0.1651 0.7366) (xy -0.1651 0.11938)
						(xy -0.17272 0.11176) (xy -0.19812 0.0762) (xy -0.2032 0.06604) (xy -0.20701 0.05715) (xy -0.21209 0.04699)
						(xy -0.2159 0.03683) (xy -0.21844 0.02667) (xy -0.22225 0.01524) (xy -0.22352 0.00508) (xy -0.22606 -0.00508)
						(xy -0.22733 -0.01651) (xy -0.22733 -0.02667) (xy -0.2286 -0.0381) (xy -0.22733 -0.04953) (xy -0.22733 -0.05969)
						(xy -0.22606 -0.07112) (xy -0.22352 -0.08128) (xy -0.22225 -0.09144) (xy -0.21844 -0.10287) (xy -0.2159 -0.11303)
						(xy -0.21209 -0.12319) (xy -0.20701 -0.13335) (xy -0.2032 -0.14224) (xy -0.19812 -0.1524) (xy -0.17272 -0.18796)
						(xy -0.1651 -0.19558) (xy -0.1651 -0.7366) (xy -0.16256 -0.76835) (xy -0.1524 -0.8001) (xy -0.13716 -0.82804)
						(xy -0.11684 -0.85344) (xy -0.09144 -0.87376) (xy -0.0635 -0.889) (xy -0.03175 -0.89916) (xy 0 -0.9017)
						(xy 0.03175 -0.89916) (xy 0.0635 -0.889) (xy 0.09144 -0.87376) (xy 0.11684 -0.85344) (xy 0.13716 -0.82804)
						(xy 0.1524 -0.8001) (xy 0.16256 -0.76835) (xy 0.1651 -0.7366) (xy 0.1651 -0.19685) (xy 0.17272 -0.18923)
						(xy 0.17907 -0.18034) (xy 0.18669 -0.17145) (xy 0.19177 -0.16256) (xy 0.19812 -0.15367) (xy 0.20828 -0.13335)
						(xy 0.21971 -0.10287) (xy 0.22225 -0.09271) (xy 0.22479 -0.08128) (xy 0.22606 -0.07112) (xy 0.2286 -0.05969)
						(xy 0.2286 -0.01651) (xy 0.22606 -0.00508) (xy 0.22479 0.00508) (xy 0.22225 0.01651) (xy 0.21971 0.02667)
						(xy 0.20828 0.05715) (xy 0.19812 0.07747) (xy 0.19177 0.08636) (xy 0.18669 0.09525) (xy 0.17907 0.10414)
						(xy 0.17272 0.11303) (xy 0.1651 0.12065) (xy 0.1651 0.7366) (xy 0.16256 0.76835) (xy 0.1524 0.8001)
						(xy 0.13716 0.82804) (xy 0.11684 0.85344) (xy 0.09144 0.87376) (xy 0.0635 0.889) (xy 0.03175 0.89916)
					)
					(width 0)
					(fill yes)
				)
			)
		)
		(pad "128" smd custom
			(at 8.850122 -4.106672 180)
			(size 0.1143 0.1143)
			(layers "F.Cu" "F.Mask" "F.Paste")
			(net "M_A_ODT3")
			(options
				(clearance outline)
				(anchor circle)
			)
			(primitives
				(gr_poly
					(pts
						(xy 0 0.9017) (xy -0.03175 0.89916) (xy -0.0635 0.889) (xy -0.09144 0.87376) (xy -0.11684 0.85344)
						(xy -0.13716 0.82804) (xy -0.1524 0.8001) (xy -0.16256 0.76835) (xy -0.1651 0.7366) (xy -0.1651 0.19685)
						(xy -0.17272 0.18923) (xy -0.17907 0.18034) (xy -0.18669 0.17145) (xy -0.19177 0.16256) (xy -0.19812 0.15367)
						(xy -0.20828 0.13335) (xy -0.21971 0.10287) (xy -0.22225 0.09271) (xy -0.22479 0.08128) (xy -0.22606 0.07112)
						(xy -0.2286 0.05969) (xy -0.2286 0.01651) (xy -0.22606 0.00508) (xy -0.22479 -0.00508) (xy -0.22225 -0.01651)
						(xy -0.21971 -0.02667) (xy -0.20828 -0.05715) (xy -0.19812 -0.07747) (xy -0.19177 -0.08636) (xy -0.18669 -0.09525)
						(xy -0.17907 -0.10414) (xy -0.17272 -0.11303) (xy -0.1651 -0.12065) (xy -0.1651 -0.7366) (xy -0.16256 -0.76835)
						(xy -0.1524 -0.8001) (xy -0.13716 -0.82804) (xy -0.11684 -0.85344) (xy -0.09144 -0.87376) (xy -0.0635 -0.889)
						(xy -0.03175 -0.89916) (xy 0 -0.9017) (xy 0.03175 -0.89916) (xy 0.0635 -0.889) (xy 0.09144 -0.87376)
						(xy 0.11684 -0.85344) (xy 0.13716 -0.82804) (xy 0.1524 -0.8001) (xy 0.16256 -0.76835) (xy 0.1651 -0.7366)
						(xy 0.1651 -0.11938) (xy 0.17272 -0.11176) (xy 0.19812 -0.0762) (xy 0.2032 -0.06604) (xy 0.20701 -0.05715)
						(xy 0.21209 -0.04699) (xy 0.2159 -0.03683) (xy 0.21844 -0.02667) (xy 0.22225 -0.01524) (xy 0.22352 -0.00508)
						(xy 0.22606 0.00508) (xy 0.22733 0.01651) (xy 0.22733 0.02667) (xy 0.2286 0.0381) (xy 0.22733 0.04953)
						(xy 0.22733 0.05969) (xy 0.22606 0.07112) (xy 0.22352 0.08128) (xy 0.22225 0.09144) (xy 0.21844 0.10287)
						(xy 0.2159 0.11303) (xy 0.21209 0.12319) (xy 0.20701 0.13335) (xy 0.2032 0.14224) (xy 0.19812 0.1524)
						(xy 0.17272 0.18796) (xy 0.1651 0.19558) (xy 0.1651 0.7366) (xy 0.16256 0.76835) (xy 0.1524 0.8001)
						(xy 0.13716 0.82804) (xy 0.11684 0.85344) (xy 0.09144 0.87376) (xy 0.0635 0.889) (xy 0.03175 0.89916)
					)
					(width 0)
					(fill yes)
				)
			)
		)
		(pad "129" smd custom
			(at 9.150096 4.106672 180)
			(size 0.1143 0.1143)
			(layers "F.Cu" "F.Mask" "F.Paste")
			(net "M_A_CS_N3")
			(options
				(clearance outline)
				(anchor circle)
			)
			(primitives
				(gr_poly
					(pts
						(xy 0 0.9017) (xy -0.03175 0.89916) (xy -0.0635 0.889) (xy -0.09144 0.87376) (xy -0.11684 0.85344)
						(xy -0.13716 0.82804) (xy -0.1524 0.8001) (xy -0.16256 0.76835) (xy -0.1651 0.7366) (xy -0.1651 -0.13462)
						(xy -0.17272 -0.14224) (xy -0.19812 -0.1778) (xy -0.2032 -0.18796) (xy -0.20701 -0.19685) (xy -0.21209 -0.20701)
						(xy -0.2159 -0.21717) (xy -0.21844 -0.22733) (xy -0.22225 -0.23876) (xy -0.22352 -0.24892) (xy -0.22606 -0.25908)
						(xy -0.22733 -0.27051) (xy -0.22733 -0.28067) (xy -0.2286 -0.2921) (xy -0.22733 -0.30353) (xy -0.22733 -0.31369)
						(xy -0.22606 -0.32512) (xy -0.22352 -0.33528) (xy -0.22225 -0.34544) (xy -0.21844 -0.35687) (xy -0.2159 -0.36703)
						(xy -0.21209 -0.37719) (xy -0.20701 -0.38735) (xy -0.2032 -0.39624) (xy -0.19812 -0.4064) (xy -0.17272 -0.44196)
						(xy -0.1651 -0.44958) (xy -0.1651 -0.7366) (xy -0.16256 -0.76835) (xy -0.1524 -0.8001) (xy -0.13716 -0.82804)
						(xy -0.11684 -0.85344) (xy -0.09144 -0.87376) (xy -0.0635 -0.889) (xy -0.03175 -0.89916) (xy 0 -0.9017)
						(xy 0.03175 -0.89916) (xy 0.0635 -0.889) (xy 0.09144 -0.87376) (xy 0.11684 -0.85344) (xy 0.13716 -0.82804)
						(xy 0.1524 -0.8001) (xy 0.16256 -0.76835) (xy 0.1651 -0.7366) (xy 0.1651 -0.44958) (xy 0.17272 -0.44196)
						(xy 0.19812 -0.4064) (xy 0.2032 -0.39624) (xy 0.20701 -0.38735) (xy 0.21209 -0.37719) (xy 0.2159 -0.36703)
						(xy 0.21844 -0.35687) (xy 0.22225 -0.34544) (xy 0.22352 -0.33528) (xy 0.22606 -0.32512) (xy 0.22733 -0.31369)
						(xy 0.22733 -0.30353) (xy 0.2286 -0.2921) (xy 0.22733 -0.28067) (xy 0.22733 -0.27051) (xy 0.22606 -0.25908)
						(xy 0.22352 -0.24892) (xy 0.22225 -0.23876) (xy 0.21844 -0.22733) (xy 0.2159 -0.21717) (xy 0.21209 -0.20701)
						(xy 0.20701 -0.19685) (xy 0.2032 -0.18796) (xy 0.19812 -0.1778) (xy 0.17272 -0.14224) (xy 0.1651 -0.13462)
						(xy 0.1651 0.7366) (xy 0.16256 0.76835) (xy 0.1524 0.8001) (xy 0.13716 0.82804) (xy 0.11684 0.85344)
						(xy 0.09144 0.87376) (xy 0.0635 0.889) (xy 0.03175 0.89916)
					)
					(width 0)
					(fill yes)
				)
			)
		)
		(pad "130" smd custom
			(at 9.45007 -4.106672 180)
			(size 0.1143 0.1143)
			(layers "F.Cu" "F.Mask" "F.Paste")
			(net "M_A_MA13")
			(options
				(clearance outline)
				(anchor circle)
			)
			(primitives
				(gr_poly
					(pts
						(xy 0 0.9017) (xy -0.03175 0.89916) (xy -0.0635 0.889) (xy -0.09144 0.87376) (xy -0.11684 0.85344)
						(xy -0.13716 0.82804) (xy -0.1524 0.8001) (xy -0.16256 0.76835) (xy -0.1651 0.7366) (xy -0.1651 0.44958)
						(xy -0.17272 0.44196) (xy -0.19812 0.4064) (xy -0.2032 0.39624) (xy -0.20701 0.38735) (xy -0.21209 0.37719)
						(xy -0.2159 0.36703) (xy -0.21844 0.35687) (xy -0.22225 0.34544) (xy -0.22352 0.33528) (xy -0.22606 0.32512)
						(xy -0.22733 0.31369) (xy -0.22733 0.30353) (xy -0.2286 0.2921) (xy -0.22733 0.28067) (xy -0.22733 0.27051)
						(xy -0.22606 0.25908) (xy -0.22352 0.24892) (xy -0.22225 0.23876) (xy -0.21844 0.22733) (xy -0.2159 0.21717)
						(xy -0.21209 0.20701) (xy -0.20701 0.19685) (xy -0.2032 0.18796) (xy -0.19812 0.1778) (xy -0.17272 0.14224)
						(xy -0.1651 0.13462) (xy -0.1651 -0.7366) (xy -0.16256 -0.76835) (xy -0.1524 -0.8001) (xy -0.13716 -0.82804)
						(xy -0.11684 -0.85344) (xy -0.09144 -0.87376) (xy -0.0635 -0.889) (xy -0.03175 -0.89916) (xy 0 -0.9017)
						(xy 0.03175 -0.89916) (xy 0.0635 -0.889) (xy 0.09144 -0.87376) (xy 0.11684 -0.85344) (xy 0.13716 -0.82804)
						(xy 0.1524 -0.8001) (xy 0.16256 -0.76835) (xy 0.1651 -0.7366) (xy 0.1651 0.13462) (xy 0.17272 0.14224)
						(xy 0.19812 0.1778) (xy 0.2032 0.18796) (xy 0.20701 0.19685) (xy 0.21209 0.20701) (xy 0.2159 0.21717)
						(xy 0.21844 0.22733) (xy 0.22225 0.23876) (xy 0.22352 0.24892) (xy 0.22606 0.25908) (xy 0.22733 0.27051)
						(xy 0.22733 0.28067) (xy 0.2286 0.2921) (xy 0.22733 0.30353) (xy 0.22733 0.31369) (xy 0.22606 0.32512)
						(xy 0.22352 0.33528) (xy 0.22225 0.34544) (xy 0.21844 0.35687) (xy 0.2159 0.36703) (xy 0.21209 0.37719)
						(xy 0.20701 0.38735) (xy 0.2032 0.39624) (xy 0.19812 0.4064) (xy 0.17272 0.44196) (xy 0.1651 0.44958)
						(xy 0.1651 0.7366) (xy 0.16256 0.76835) (xy 0.1524 0.8001) (xy 0.13716 0.82804) (xy 0.11684 0.85344)
						(xy 0.09144 0.87376) (xy 0.0635 0.889) (xy 0.03175 0.89916)
					)
					(width 0)
					(fill yes)
				)
			)
		)
		(pad "131" smd custom
			(at 9.750044 4.106672 180)
			(size 0.1143 0.1143)
			(layers "F.Cu" "F.Mask" "F.Paste")
			(net "PV_VDDR")
			(options
				(clearance outline)
				(anchor circle)
			)
			(primitives
				(gr_poly
					(pts
						(xy 0 0.9017) (xy -0.03175 0.89916) (xy -0.0635 0.889) (xy -0.09144 0.87376) (xy -0.11684 0.85344)
						(xy -0.13716 0.82804) (xy -0.1524 0.8001) (xy -0.16256 0.76835) (xy -0.1651 0.7366) (xy -0.1651 0.11938)
						(xy -0.17272 0.11176) (xy -0.19812 0.0762) (xy -0.2032 0.06604) (xy -0.20701 0.05715) (xy -0.21209 0.04699)
						(xy -0.2159 0.03683) (xy -0.21844 0.02667) (xy -0.22225 0.01524) (xy -0.22352 0.00508) (xy -0.22606 -0.00508)
						(xy -0.22733 -0.01651) (xy -0.22733 -0.02667) (xy -0.2286 -0.0381) (xy -0.22733 -0.04953) (xy -0.22733 -0.05969)
						(xy -0.22606 -0.07112) (xy -0.22352 -0.08128) (xy -0.22225 -0.09144) (xy -0.21844 -0.10287) (xy -0.2159 -0.11303)
						(xy -0.21209 -0.12319) (xy -0.20701 -0.13335) (xy -0.2032 -0.14224) (xy -0.19812 -0.1524) (xy -0.17272 -0.18796)
						(xy -0.1651 -0.19558) (xy -0.1651 -0.7366) (xy -0.16256 -0.76835) (xy -0.1524 -0.8001) (xy -0.13716 -0.82804)
						(xy -0.11684 -0.85344) (xy -0.09144 -0.87376) (xy -0.0635 -0.889) (xy -0.03175 -0.89916) (xy 0 -0.9017)
						(xy 0.03175 -0.89916) (xy 0.0635 -0.889) (xy 0.09144 -0.87376) (xy 0.11684 -0.85344) (xy 0.13716 -0.82804)
						(xy 0.1524 -0.8001) (xy 0.16256 -0.76835) (xy 0.1651 -0.7366) (xy 0.1651 -0.19685) (xy 0.17272 -0.18923)
						(xy 0.17907 -0.18034) (xy 0.18669 -0.17145) (xy 0.19177 -0.16256) (xy 0.19812 -0.15367) (xy 0.20828 -0.13335)
						(xy 0.21971 -0.10287) (xy 0.22225 -0.09271) (xy 0.22479 -0.08128) (xy 0.22606 -0.07112) (xy 0.2286 -0.05969)
						(xy 0.2286 -0.01651) (xy 0.22606 -0.00508) (xy 0.22479 0.00508) (xy 0.22225 0.01651) (xy 0.21971 0.02667)
						(xy 0.20828 0.05715) (xy 0.19812 0.07747) (xy 0.19177 0.08636) (xy 0.18669 0.09525) (xy 0.17907 0.10414)
						(xy 0.17272 0.11303) (xy 0.1651 0.12065) (xy 0.1651 0.7366) (xy 0.16256 0.76835) (xy 0.1524 0.8001)
						(xy 0.13716 0.82804) (xy 0.11684 0.85344) (xy 0.09144 0.87376) (xy 0.0635 0.889) (xy 0.03175 0.89916)
					)
					(width 0)
					(fill yes)
				)
			)
		)
		(pad "132" smd custom
			(at 10.050018 -4.106672 180)
			(size 0.1143 0.1143)
			(layers "F.Cu" "F.Mask" "F.Paste")
			(net "PV_VDDR")
			(options
				(clearance outline)
				(anchor circle)
			)
			(primitives
				(gr_poly
					(pts
						(xy 0 0.9017) (xy -0.03175 0.89916) (xy -0.0635 0.889) (xy -0.09144 0.87376) (xy -0.11684 0.85344)
						(xy -0.13716 0.82804) (xy -0.1524 0.8001) (xy -0.16256 0.76835) (xy -0.1651 0.7366) (xy -0.1651 0.19685)
						(xy -0.17272 0.18923) (xy -0.17907 0.18034) (xy -0.18669 0.17145) (xy -0.19177 0.16256) (xy -0.19812 0.15367)
						(xy -0.20828 0.13335) (xy -0.21971 0.10287) (xy -0.22225 0.09271) (xy -0.22479 0.08128) (xy -0.22606 0.07112)
						(xy -0.2286 0.05969) (xy -0.2286 0.01651) (xy -0.22606 0.00508) (xy -0.22479 -0.00508) (xy -0.22225 -0.01651)
						(xy -0.21971 -0.02667) (xy -0.20828 -0.05715) (xy -0.19812 -0.07747) (xy -0.19177 -0.08636) (xy -0.18669 -0.09525)
						(xy -0.17907 -0.10414) (xy -0.17272 -0.11303) (xy -0.1651 -0.12065) (xy -0.1651 -0.7366) (xy -0.16256 -0.76835)
						(xy -0.1524 -0.8001) (xy -0.13716 -0.82804) (xy -0.11684 -0.85344) (xy -0.09144 -0.87376) (xy -0.0635 -0.889)
						(xy -0.03175 -0.89916) (xy 0 -0.9017) (xy 0.03175 -0.89916) (xy 0.0635 -0.889) (xy 0.09144 -0.87376)
						(xy 0.11684 -0.85344) (xy 0.13716 -0.82804) (xy 0.1524 -0.8001) (xy 0.16256 -0.76835) (xy 0.1651 -0.7366)
						(xy 0.1651 -0.11938) (xy 0.17272 -0.11176) (xy 0.19812 -0.0762) (xy 0.2032 -0.06604) (xy 0.20701 -0.05715)
						(xy 0.21209 -0.04699) (xy 0.2159 -0.03683) (xy 0.21844 -0.02667) (xy 0.22225 -0.01524) (xy 0.22352 -0.00508)
						(xy 0.22606 0.00508) (xy 0.22733 0.01651) (xy 0.22733 0.02667) (xy 0.2286 0.0381) (xy 0.22733 0.04953)
						(xy 0.22733 0.05969) (xy 0.22606 0.07112) (xy 0.22352 0.08128) (xy 0.22225 0.09144) (xy 0.21844 0.10287)
						(xy 0.2159 0.11303) (xy 0.21209 0.12319) (xy 0.20701 0.13335) (xy 0.2032 0.14224) (xy 0.19812 0.1524)
						(xy 0.17272 0.18796) (xy 0.1651 0.19558) (xy 0.1651 0.7366) (xy 0.16256 0.76835) (xy 0.1524 0.8001)
						(xy 0.13716 0.82804) (xy 0.11684 0.85344) (xy 0.09144 0.87376) (xy 0.0635 0.889) (xy 0.03175 0.89916)
					)
					(width 0)
					(fill yes)
				)
			)
		)
	)
)
